(kicad_pcb
	(version 20241229)
	(generator "pcbnew")
	(generator_version "9.0")
	(general
		(thickness 1.63)
		(legacy_teardrops no)
	)
	(paper "A4")
	(title_block
		(title "CM4 Baseboard")
		(date "2026-01-05")
		(rev "1.1.1")
		(company "Antmicro Ltd")
		(comment 1 "www.antmicro.com")
		(comment 9 "footprints 90-92 of 506")
	)
	(layers
		(0 "F.Cu" signal)
		(4 "In1.Cu" power)
		(6 "In2.Cu" power)
		(8 "In3.Cu" signal)
		(10 "In4.Cu" signal)
		(2 "B.Cu" signal)
		(9 "F.Adhes" user "F.Adhesive")
		(11 "B.Adhes" user "B.Adhesive")
		(13 "F.Paste" user)
		(15 "B.Paste" user)
		(5 "F.SilkS" user "F.Silkscreen")
		(7 "B.SilkS" user "B.Silkscreen")
		(1 "F.Mask" user)
		(3 "B.Mask" user)
		(17 "Dwgs.User" user "User.Drawings")
		(19 "Cmts.User" user "User.Comments")
		(21 "Eco1.User" user "User.Eco1")
		(23 "Eco2.User" user "User.Eco2")
		(25 "Edge.Cuts" user)
		(27 "Margin" user)
		(31 "F.CrtYd" user "F.Courtyard")
		(29 "B.CrtYd" user "B.Courtyard")
		(35 "F.Fab" user)
		(33 "B.Fab" user)
	)
	(footprint "antmicro-footprints:SOT-23-3"
		(layer "F.Cu")
		(at 107.492962 152.692)
		(property "Reference" "Q202"
			(at 0.775 -0.667 0)
			(layer "F.SilkS")
			(effects
				(font
					(size 0.7 0.7)
					(thickness 0.15)
				)
				(justify left bottom)
			)
		)
		(property "Value" "SSM3J332R"
			(at -1.9 2.7 0)
			(layer "F.Fab")
			(effects
				(font
					(size 0.7 0.7)
					(thickness 0.15)
				)
				(justify left bottom)
			)
		)
		(property "Datasheet" "https://www.mouser.com/datasheet/2/408/SSM3J332R_datasheet_en_20181015-1150575.pdf"
			(at 0 0 0)
			(layer "F.Fab")
			(hide yes)
			(effects
				(font
					(size 1.27 1.27)
					(thickness 0.15)
				)
			)
		)
		(property "MPN" "SSM3J332R,LF"
			(at 0 0 0)
			(unlocked yes)
			(layer "F.Fab")
			(hide yes)
			(effects
				(font
					(size 1 1)
					(thickness 0.15)
				)
			)
		)
		(property "Manufacturer" "Toshiba"
			(at 0 0 0)
			(unlocked yes)
			(layer "F.Fab")
			(hide yes)
			(effects
				(font
					(size 1 1)
					(thickness 0.15)
				)
			)
		)
		(property "Author" "Antmicro"
			(at 0 0 0)
			(unlocked yes)
			(layer "F.Fab")
			(hide yes)
			(effects
				(font
					(size 1 1)
					(thickness 0.15)
				)
			)
		)
		(property "License" "Apache-2.0"
			(at 0 0 0)
			(unlocked yes)
			(layer "F.Fab")
			(hide yes)
			(effects
				(font
					(size 1 1)
					(thickness 0.15)
				)
			)
		)
		(sheetname "/Compute module/")
		(sheetfile "compute-module.kicad_sch")
		(attr smd)
		(fp_line
			(start -1.45 -1.35)
			(end -0.85 -1.35)
			(stroke
				(width 0.15)
				(type solid)
			)
			(layer "F.SilkS")
		)
		(fp_line
			(start -0.85 -1.35)
			(end -0.7 -1.5)
			(stroke
				(width 0.15)
				(type solid)
			)
			(layer "F.SilkS")
		)
		(fp_line
			(start -0.7 1.5)
			(end -0.7 1.35)
			(stroke
				(width 0.15)
				(type solid)
			)
			(layer "F.SilkS")
		)
		(fp_line
			(start 0.7 -1.5)
			(end -0.7 -1.5)
			(stroke
				(width 0.15)
				(type solid)
			)
			(layer "F.SilkS")
		)
		(fp_line
			(start 0.7 -0.4)
			(end 0.7 -1.5)
			(stroke
				(width 0.15)
				(type solid)
			)
			(layer "F.SilkS")
		)
		(fp_line
			(start 0.7 0.4)
			(end 0.7 1.5)
			(stroke
				(width 0.15)
				(type solid)
			)
			(layer "F.SilkS")
		)
		(fp_line
			(start 0.7 1.5)
			(end -0.7 1.5)
			(stroke
				(width 0.15)
				(type solid)
			)
			(layer "F.SilkS")
		)
		(fp_line
			(start -1.75 -0.5)
			(end -1.75 -1.4)
			(stroke
				(width 0.05)
				(type solid)
			)
			(layer "F.CrtYd")
		)
		(fp_line
			(start -1.75 0.5)
			(end -0.85 0.5)
			(stroke
				(width 0.05)
				(type solid)
			)
			(layer "F.CrtYd")
		)
		(fp_line
			(start -1.75 1.4)
			(end -1.75 0.5)
			(stroke
				(width 0.05)
				(type solid)
			)
			(layer "F.CrtYd")
		)
		(fp_line
			(start -0.9 -1.6)
			(end -0.9 -1.4)
			(stroke
				(width 0.05)
				(type solid)
			)
			(layer "F.CrtYd")
		)
		(fp_line
			(start -0.9 -1.6)
			(end 0.825 -1.6)
			(stroke
				(width 0.05)
				(type solid)
			)
			(layer "F.CrtYd")
		)
		(fp_line
			(start -0.9 -1.4)
			(end -1.75 -1.4)
			(stroke
				(width 0.05)
				(type solid)
			)
			(layer "F.CrtYd")
		)
		(fp_line
			(start -0.85 -0.5)
			(end -1.75 -0.5)
			(stroke
				(width 0.05)
				(type solid)
			)
			(layer "F.CrtYd")
		)
		(fp_line
			(start -0.85 0.5)
			(end -0.85 -0.5)
			(stroke
				(width 0.05)
				(type solid)
			)
			(layer "F.CrtYd")
		)
		(fp_line
			(start -0.85 1.4)
			(end -1.75 1.4)
			(stroke
				(width 0.05)
				(type solid)
			)
			(layer "F.CrtYd")
		)
		(fp_line
			(start -0.85 1.65)
			(end -0.85 1.4)
			(stroke
				(width 0.05)
				(type solid)
			)
			(layer "F.CrtYd")
		)
		(fp_line
			(start 0.825 -1.6)
			(end 0.825 -0.45)
			(stroke
				(width 0.05)
				(type solid)
			)
			(layer "F.CrtYd")
		)
		(fp_line
			(start 0.825 -0.45)
			(end 1.75 -0.45)
			(stroke
				(width 0.05)
				(type solid)
			)
			(layer "F.CrtYd")
		)
		(fp_line
			(start 0.85 0.45)
			(end 0.85 1.65)
			(stroke
				(width 0.05)
				(type solid)
			)
			(layer "F.CrtYd")
		)
		(fp_line
			(start 0.85 1.65)
			(end -0.85 1.65)
			(stroke
				(width 0.05)
				(type solid)
			)
			(layer "F.CrtYd")
		)
		(fp_line
			(start 1.75 -0.45)
			(end 1.75 0.45)
			(stroke
				(width 0.05)
				(type solid)
			)
			(layer "F.CrtYd")
		)
		(fp_line
			(start 1.75 0.45)
			(end 0.85 0.45)
			(stroke
				(width 0.05)
				(type solid)
			)
			(layer "F.CrtYd")
		)
		(fp_line
			(start -0.712 -1.325)
			(end -0.712 1.523)
			(stroke
				(width 0.15)
				(type solid)
			)
			(layer "F.Fab")
		)
		(fp_line
			(start -0.712 1.519)
			(end 0.688 1.519)
			(stroke
				(width 0.15)
				(type solid)
			)
			(layer "F.Fab")
		)
		(fp_line
			(start -0.437 -1.526)
			(end -0.712 -1.325)
			(stroke
				(width 0.15)
				(type solid)
			)
			(layer "F.Fab")
		)
		(fp_line
			(start -0.437 -1.526)
			(end 0.688 -1.526)
			(stroke
				(width 0.15)
				(type solid)
			)
			(layer "F.Fab")
		)
		(fp_line
			(start 0.688 1.519)
			(end 0.688 -1.52)
			(stroke
				(width 0.15)
				(type solid)
			)
			(layer "F.Fab")
		)
		(fp_text user "License: Apache-2.0"
			(at -1.8 6.8 0)
			(layer "F.Fab")
			(effects
				(font
					(size 0.7 0.7)
					(thickness 0.15)
				)
				(justify left bottom)
			)
		)
		(fp_text user "Author: Antmicro"
			(at -1.837 5.3 0)
			(layer "F.Fab")
			(effects
				(font
					(size 0.7 0.7)
					(thickness 0.15)
				)
				(justify left bottom)
			)
		)
		(fp_text user "${REFERENCE}"
			(at -1.837 4 0)
			(layer "F.Fab")
			(effects
				(font
					(size 0.7 0.7)
					(thickness 0.15)
				)
				(justify left bottom)
			)
		)
		(pad "1" smd roundrect
			(at -1.1 -0.951)
			(size 1 0.6)
			(layers "F.Cu" "F.Mask" "F.Paste")
			(roundrect_rratio 0.15)
			(net 327 "Net-(Q201-D)")
			(pinfunction "G")
			(pintype "input")
		)
		(pad "2" smd roundrect
			(at -1.1 0.949)
			(size 1 0.6)
			(layers "F.Cu" "F.Mask" "F.Paste")
			(roundrect_rratio 0.15)
			(net 10 "+5V")
			(pinfunction "S")
			(pintype "passive")
		)
		(pad "3" smd roundrect
			(at 1.1 -0.0005)
			(size 1 0.6)
			(layers "F.Cu" "F.Mask" "F.Paste")
			(roundrect_rratio 0.15)
			(net 257 "/Compute module/Pf_5V.HPD")
			(pinfunction "D")
			(pintype "passive")
		)
	)
	(footprint "antmicro-footprints:Vishay_PowerPAK_1212-8_Single"
		(layer "F.Cu")
		(at 75.342962 129.6915 -90)
		(descr "PowerPAK 1212-8 Single")
		(tags "Vishay PowerPAK 1212-8 Single")
		(property "Reference" "Q902"
			(at -1.95 -1.4 0)
			(layer "F.SilkS")
			(effects
				(font
					(size 0.7 0.7)
					(thickness 0.15)
				)
				(justify right bottom)
			)
		)
		(property "Value" "SQS401EN-T1_BE3"
			(at 0 2.7 90)
			(layer "F.Fab")
			(effects
				(font
					(size 0.7 0.7)
					(thickness 0.15)
				)
				(justify right bottom)
			)
		)
		(property "Datasheet" "https://www.vishay.com/docs/65529/sqs401en.pdf"
			(at 0 0 270)
			(layer "F.Fab")
			(hide yes)
			(effects
				(font
					(size 1.27 1.27)
					(thickness 0.15)
				)
			)
		)
		(property "MPN" "SQS401EN-T1_BE3"
			(at 0 0 270)
			(unlocked yes)
			(layer "F.Fab")
			(hide yes)
			(effects
				(font
					(size 1 1)
					(thickness 0.15)
				)
			)
		)
		(property "Manufacturer" "Vishay"
			(at 0 0 270)
			(unlocked yes)
			(layer "F.Fab")
			(hide yes)
			(effects
				(font
					(size 1 1)
					(thickness 0.15)
				)
			)
		)
		(property "Author" "Antmicro"
			(at 0 0 270)
			(unlocked yes)
			(layer "F.Fab")
			(hide yes)
			(effects
				(font
					(size 1 1)
					(thickness 0.15)
				)
			)
		)
		(property "License" "Apache-2.0"
			(at 0 0 270)
			(unlocked yes)
			(layer "F.Fab")
			(hide yes)
			(effects
				(font
					(size 1 1)
					(thickness 0.15)
				)
			)
		)
		(sheetname "/USB/")
		(sheetfile "usb.kicad_sch")
		(attr smd)
		(fp_line
			(start -1.635 1.634)
			(end 1.634 1.634)
			(stroke
				(width 0.15)
				(type solid)
			)
			(layer "F.SilkS")
		)
		(fp_line
			(start -1.635 1.3)
			(end -1.635 1.634)
			(stroke
				(width 0.15)
				(type solid)
			)
			(layer "F.SilkS")
		)
		(fp_line
			(start 1.634 1.3)
			(end 1.634 1.634)
			(stroke
				(width 0.15)
				(type solid)
			)
			(layer "F.SilkS")
		)
		(fp_line
			(start -1.651 -1.651)
			(end -1.651 -1.317)
			(stroke
				(width 0.15)
				(type solid)
			)
			(layer "F.SilkS")
		)
		(fp_line
			(start -1.651 -1.651)
			(end 1.648 -1.651)
			(stroke
				(width 0.15)
				(type solid)
			)
			(layer "F.SilkS")
		)
		(fp_line
			(start 1.648 -1.651)
			(end 1.648 -1.317)
			(stroke
				(width 0.15)
				(type solid)
			)
			(layer "F.SilkS")
		)
		(fp_circle
			(center -1.9 -1.4)
			(end -1.85 -1.4)
			(stroke
				(width 0.15)
				(type solid)
			)
			(fill yes)
			(layer "F.SilkS")
		)
		(fp_rect
			(start -2 -1.8)
			(end 2 1.798)
			(stroke
				(width 0.05)
				(type solid)
			)
			(fill no)
			(layer "F.CrtYd")
		)
		(fp_line
			(start -1.6425 -1.4175)
			(end -1.4175 -1.6425)
			(stroke
				(width 0.15)
				(type solid)
			)
			(layer "F.Fab")
		)
		(fp_rect
			(start -1.651 -1.651)
			(end 1.648 1.648)
			(stroke
				(width 0.15)
				(type solid)
			)
			(fill no)
			(layer "F.Fab")
		)
		(fp_text user "Author: Antmicro"
			(at -8 5.9 270)
			(layer "F.Fab")
			(effects
				(font
					(size 0.7 0.7)
					(thickness 0.15)
				)
				(justify left bottom)
			)
		)
		(fp_text user "${REFERENCE}"
			(at -8 4.7 270)
			(layer "F.Fab")
			(effects
				(font
					(size 0.7 0.7)
					(thickness 0.15)
				)
				(justify left bottom)
			)
		)
		(fp_text user "License: Apache-2.0"
			(at -8 7.1 270)
			(layer "F.Fab")
			(effects
				(font
					(size 0.7 0.7)
					(thickness 0.15)
				)
				(justify left bottom)
			)
		)
		(pad "1" smd rect
			(at -1.436 -0.99 270)
			(size 0.99 0.405)
			(layers "F.Cu" "F.Mask" "F.Paste")
			(net 26 "/USB/USBD_VBUS")
			(pinfunction "S")
			(pintype "passive")
		)
		(pad "2" smd rect
			(at -1.436 -0.332 270)
			(size 0.99 0.405)
			(layers "F.Cu" "F.Mask" "F.Paste")
			(net 26 "/USB/USBD_VBUS")
			(pinfunction "S")
			(pintype "passive")
		)
		(pad "3" smd rect
			(at -1.436 0.33 270)
			(size 0.99 0.405)
			(layers "F.Cu" "F.Mask" "F.Paste")
			(net 26 "/USB/USBD_VBUS")
			(pinfunction "S")
			(pintype "passive")
		)
		(pad "4" smd rect
			(at -1.436 0.988 270)
			(size 0.99 0.405)
			(layers "F.Cu" "F.Mask" "F.Paste")
			(net 341 "Net-(Q902-G)")
			(pinfunction "G")
			(pintype "input")
		)
		(pad "5" smd custom
			(at 0.557 0 270)
			(size 1.725 2.235)
			(layers "F.Cu" "F.Mask" "F.Paste")
			(net 443 "/Supply/V_{BUS}")
			(pinfunction "D")
			(pintype "passive")
			(zone_connect 2)
			(options
				(clearance outline)
				(anchor rect)
			)
			(primitives
				(gr_poly
					(pts
						(xy 0.8625 0.1275) (xy 0.8625 -0.1275) (xy 1.3725 -0.1275) (xy 1.3725 -0.5325) (xy 0.8625 -0.5325)
						(xy 0.8625 -0.7875) (xy 1.3725 -0.7875) (xy 1.3725 -1.195) (xy 0.6125 -1.195) (xy 0.6125 1.195)
						(xy 1.3725 1.195) (xy 1.3725 0.7875) (xy 0.8625 0.7875) (xy 0.8625 0.5325) (xy 1.3725 0.5325)
						(xy 1.3725 0.1275)
					)
					(width 0)
					(fill yes)
				)
			)
		)
	)
	(footprint "antmicro-footprints:Nexperia_DFN-10_2.5x1mm_P0.5mm"
		(layer "F.Cu")
		(at 79.530962 121.3665)
		(property "Reference" "D902"
			(at -1.443 1.61 0)
			(layer "F.SilkS")
			(effects
				(font
					(size 0.7 0.7)
					(thickness 0.15)
				)
				(justify left bottom)
			)
		)
		(property "Value" "PUSB3F96X_PASS"
			(at -0.016 1.705 0)
			(layer "F.Fab")
			(effects
				(font
					(size 0.7 0.7)
					(thickness 0.15)
				)
				(justify left bottom)
			)
		)
		(property "Datasheet" "https://mouser.com/datasheet/2/916/PUSB3F96-1600324.pdf"
			(at 0 0 0)
			(layer "F.Fab")
			(hide yes)
			(effects
				(font
					(size 1.27 1.27)
					(thickness 0.15)
				)
			)
		)
		(property "Manufacturer" "Nexperia"
			(at 0 0 0)
			(unlocked yes)
			(layer "F.Fab")
			(hide yes)
			(effects
				(font
					(size 1 1)
					(thickness 0.15)
				)
			)
		)
		(property "MPN" "PUSB3F96X"
			(at 0 0 0)
			(unlocked yes)
			(layer "F.Fab")
			(hide yes)
			(effects
				(font
					(size 1 1)
					(thickness 0.15)
				)
			)
		)
		(property "Author" "Antmicro"
			(at 0 0 0)
			(unlocked yes)
			(layer "F.Fab")
			(hide yes)
			(effects
				(font
					(size 1 1)
					(thickness 0.15)
				)
			)
		)
		(property "License" "Apache-2.0"
			(at 0 0 0)
			(unlocked yes)
			(layer "F.Fab")
			(hide yes)
			(effects
				(font
					(size 1 1)
					(thickness 0.15)
				)
			)
		)
		(sheetname "/USB/")
		(sheetfile "usb.kicad_sch")
		(attr smd)
		(fp_line
			(start -1.375 -0.4)
			(end -1.375 0.4)
			(stroke
				(width 0.15)
				(type solid)
			)
			(layer "F.SilkS")
		)
		(fp_line
			(start 1.375 0.4)
			(end 1.375 -0.4)
			(stroke
				(width 0.15)
				(type solid)
			)
			(layer "F.SilkS")
		)
		(fp_circle
			(center -1.4 0.7)
			(end -1.349 0.7)
			(stroke
				(width 0.15)
				(type solid)
			)
			(fill yes)
			(layer "F.SilkS")
		)
		(fp_rect
			(start -1.4 -0.725)
			(end 1.4 0.725)
			(stroke
				(width 0.05)
				(type solid)
			)
			(fill no)
			(layer "F.CrtYd")
		)
		(fp_line
			(start -1.25 -0.5)
			(end -1.25 0.15)
			(stroke
				(width 0.15)
				(type solid)
			)
			(layer "F.Fab")
		)
		(fp_line
			(start -1.25 0.15)
			(end -0.9 0.5)
			(stroke
				(width 0.15)
				(type solid)
			)
			(layer "F.Fab")
		)
		(fp_line
			(start -0.9 0.5)
			(end 1.25 0.5)
			(stroke
				(width 0.15)
				(type solid)
			)
			(layer "F.Fab")
		)
		(fp_line
			(start 1.25 -0.5)
			(end -1.25 -0.5)
			(stroke
				(width 0.15)
				(type solid)
			)
			(layer "F.Fab")
		)
		(fp_line
			(start 1.25 0.5)
			(end 1.25 -0.5)
			(stroke
				(width 0.15)
				(type solid)
			)
			(layer "F.Fab")
		)
		(fp_text user "License: Apache-2.0"
			(at -1.367 6.105 0)
			(layer "F.Fab")
			(effects
				(font
					(size 0.7 0.7)
					(thickness 0.15)
				)
				(justify left bottom)
			)
		)
		(fp_text user "Author: Antmicro"
			(at -1.367 4.905 0)
			(layer "F.Fab")
			(effects
				(font
					(size 0.7 0.7)
					(thickness 0.15)
				)
				(justify left bottom)
			)
		)
		(fp_text user "${REFERENCE}"
			(at -1.367 3.704 0)
			(layer "F.Fab")
			(effects
				(font
					(size 0.7 0.7)
					(thickness 0.15)
				)
				(justify left bottom)
			)
		)
		(pad "1" smd rect
			(at -1 0.3875)
			(size 0.2 0.475)
			(layers "F.Cu" "F.Mask" "F.Paste")
			(net 207 "/USB/USBD_CC1")
			(pinfunction "CH1")
			(pintype "passive")
			(solder_mask_margin 0.05)
		)
		(pad "2" smd rect
			(at -0.5 0.3875)
			(size 0.2 0.475)
			(layers "F.Cu" "F.Mask" "F.Paste")
			(net 208 "/USB/USBD_CC2")
			(pinfunction "CH2")
			(pintype "passive")
			(solder_mask_margin 0.05)
		)
		(pad "3" smd rect
			(at 0 0.3875)
			(size 0.2 0.475)
			(layers "F.Cu" "F.Mask" "F.Paste")
			(net 3 "GND")
			(pinfunction "GND")
			(pintype "passive")
			(solder_mask_margin 0.05)
		)
		(pad "4" smd rect
			(at 0.5 0.3875)
			(size 0.2 0.475)
			(layers "F.Cu" "F.Mask" "F.Paste")
			(net 209 "/USB/DD_P")
			(pinfunction "CH3")
			(pintype "passive")
			(solder_mask_margin 0.05)
		)
		(pad "5" smd rect
			(at 1 0.3875)
			(size 0.2 0.475)
			(layers "F.Cu" "F.Mask" "F.Paste")
			(net 210 "/USB/DD_N")
			(pinfunction "CH4")
			(pintype "passive")
			(solder_mask_margin 0.05)
		)
		(pad "6" smd rect
			(at 1 -0.3875)
			(size 0.2 0.475)
			(layers "F.Cu" "F.Mask" "F.Paste")
			(net 210 "/USB/DD_N")
			(pinfunction "CH4")
			(pintype "passive")
			(solder_mask_margin 0.05)
		)
		(pad "7" smd rect
			(at 0.5 -0.3875)
			(size 0.2 0.475)
			(layers "F.Cu" "F.Mask" "F.Paste")
			(net 209 "/USB/DD_P")
			(pinfunction "CH3")
			(pintype "passive")
			(solder_mask_margin 0.05)
		)
		(pad "8" smd rect
			(at 0 -0.3875)
			(size 0.2 0.475)
			(layers "F.Cu" "F.Mask" "F.Paste")
			(net 3 "GND")
			(pinfunction "GND")
			(pintype "passive")
			(solder_mask_margin 0.05)
		)
		(pad "9" smd rect
			(at -0.501 -0.3875)
			(size 0.2 0.475)
			(layers "F.Cu" "F.Mask" "F.Paste")
			(net 208 "/USB/USBD_CC2")
			(pinfunction "CH2")
			(pintype "passive")
			(solder_mask_margin 0.05)
		)
		(pad "10" smd rect
			(at -1 -0.3875)
			(size 0.2 0.475)
			(layers "F.Cu" "F.Mask" "F.Paste")
			(net 207 "/USB/USBD_CC1")
			(pinfunction "CH1")
			(pintype "passive")
			(solder_mask_margin 0.05)
		)
	)
)
